(kicad_pcb
	(version 20260206)
	(generator "pcbnew")
	(generator_version "10.0")
	(general
		(thickness 1.6)
		(legacy_teardrops no)
	)
	(paper "A4")
	(title_block
		(title "panther-plus-userver — 13130-1b_20150205.brd")
		(comment 1 "Honey Badger (Wiwynn) / footprint 894 of 1509 (DIMM1), pads 184-190 of 210")
	)
	(layers
		(0 "F.Cu" signal "TOP")
		(4 "In1.Cu" signal "L2")
		(6 "In2.Cu" signal "L3")
		(8 "In3.Cu" signal "L4")
		(10 "In4.Cu" signal "L5")
		(12 "In5.Cu" signal "L6")
		(14 "In6.Cu" signal "L7")
		(16 "In7.Cu" signal "L8")
		(18 "In8.Cu" signal "L9")
		(20 "In9.Cu" signal "L10")
		(22 "In10.Cu" signal "L11")
		(2 "B.Cu" signal "BOTTOM")
		(9 "F.Adhes" user "F.Adhesive")
		(11 "B.Adhes" user "B.Adhesive")
		(13 "F.Paste" user "Package Geometry/Pastemask Top")
		(15 "B.Paste" user "Package Geometry/Pastemask Bottom")
		(5 "F.SilkS" user "Ref Des/Silkscreen Top")
		(7 "B.SilkS" user "Ref Des/Silkscreen Bottom")
		(1 "F.Mask" user "Board Geometry/Soldermask Top")
		(3 "B.Mask" user "Board Geometry/Soldermask Bottom")
		(17 "Dwgs.User" user "User.Drawings")
		(19 "Cmts.User" user "User.Comments")
		(21 "Eco1.User" user "User.Eco1")
		(23 "Eco2.User" user "User.Eco2")
		(25 "Edge.Cuts" user "Board Geometry/Outline")
		(27 "Margin" user)
		(31 "F.CrtYd" user "Package Geometry/Place Bound Top")
		(29 "B.CrtYd" user "Package Geometry/Place Bound Bottom")
		(35 "F.Fab" user "Ref Des/Assembly Top")
		(33 "B.Fab" user "Ref Des/Assembly Bottom")
	)
	(footprint ""
		(layer "B.Cu")
		(at 158.500064 -66.699892 180)
		(property "Reference" "DIMM1"
			(at 0 0 0)
			(layer "B.SilkS")
			(hide yes)
			(effects
				(font
					(size 1.27 1.27)
				)
				(justify mirror)
			)
		)
		(property "Value" "DDR3-204P-142-COLAY-1-GP-U"
			(at 41.312338 -16.676878 180)
			(unlocked yes)
			(layer "B.Fab")
			(hide yes)
			(effects
				(font
					(size 1.016 1.016)
					(thickness 0.1524)
				)
				(justify mirror)
			)
		)
		(property "Device Type" "AS0A626-J8R6-7H-COLAY-1"
			(at 41.312338 -18.200878 180)
			(unlocked yes)
			(layer "B.Fab")
			(hide yes)
			(effects
				(font
					(size 1.016 1.016)
					(thickness 0.1524)
				)
				(justify mirror)
			)
		)
		(duplicate_pad_numbers_are_jumpers no)
		(pad "182" smd custom
			(at 25.049988 4.100068)
			(size 0.1143 0.1143)
			(layers "B.Cu" "B.Mask" "B.Paste")
			(net "M_A_DQ61")
			(options
				(clearance outline)
				(anchor circle)
			)
			(primitives
				(gr_poly
					(pts
						(xy 0 -0.9017) (xy -0.03175 -0.89916) (xy -0.0635 -0.889) (xy -0.09144 -0.87376) (xy -0.11684 -0.85344)
						(xy -0.13716 -0.82804) (xy -0.1524 -0.8001) (xy -0.16256 -0.76835) (xy -0.1651 -0.7366) (xy -0.1651 0.13462)
						(xy -0.17272 0.14224) (xy -0.19812 0.1778) (xy -0.2032 0.18796) (xy -0.20701 0.19685) (xy -0.21209 0.20701)
						(xy -0.2159 0.21717) (xy -0.21844 0.22733) (xy -0.22225 0.23876) (xy -0.22352 0.24892) (xy -0.22606 0.25908)
						(xy -0.22733 0.27051) (xy -0.22733 0.28067) (xy -0.2286 0.2921) (xy -0.22733 0.30353) (xy -0.22733 0.31369)
						(xy -0.22606 0.32512) (xy -0.22352 0.33528) (xy -0.22225 0.34544) (xy -0.21844 0.35687) (xy -0.2159 0.36703)
						(xy -0.21209 0.37719) (xy -0.20701 0.38735) (xy -0.2032 0.39624) (xy -0.19812 0.4064) (xy -0.17272 0.44196)
						(xy -0.1651 0.44958) (xy -0.1651 0.7366) (xy -0.16256 0.76835) (xy -0.1524 0.8001) (xy -0.13716 0.82804)
						(xy -0.11684 0.85344) (xy -0.09144 0.87376) (xy -0.0635 0.889) (xy -0.03175 0.89916) (xy 0 0.9017)
						(xy 0.03175 0.89916) (xy 0.0635 0.889) (xy 0.09144 0.87376) (xy 0.11684 0.85344) (xy 0.13716 0.82804)
						(xy 0.1524 0.8001) (xy 0.16256 0.76835) (xy 0.1651 0.7366) (xy 0.1651 0.44958) (xy 0.17272 0.44196)
						(xy 0.19812 0.4064) (xy 0.2032 0.39624) (xy 0.20701 0.38735) (xy 0.21209 0.37719) (xy 0.2159 0.36703)
						(xy 0.21844 0.35687) (xy 0.22225 0.34544) (xy 0.22352 0.33528) (xy 0.22606 0.32512) (xy 0.22733 0.31369)
						(xy 0.22733 0.30353) (xy 0.2286 0.2921) (xy 0.22733 0.28067) (xy 0.22733 0.27051) (xy 0.22606 0.25908)
						(xy 0.22352 0.24892) (xy 0.22225 0.23876) (xy 0.21844 0.22733) (xy 0.2159 0.21717) (xy 0.21209 0.20701)
						(xy 0.20701 0.19685) (xy 0.2032 0.18796) (xy 0.19812 0.1778) (xy 0.17272 0.14224) (xy 0.1651 0.13462)
						(xy 0.1651 -0.7366) (xy 0.16256 -0.76835) (xy 0.1524 -0.8001) (xy 0.13716 -0.82804) (xy 0.11684 -0.85344)
						(xy 0.09144 -0.87376) (xy 0.0635 -0.889) (xy 0.03175 -0.89916)
					)
					(width 0)
					(fill yes)
				)
			)
		)
		(pad "183" smd custom
			(at 25.349962 -4.100068)
			(size 0.1143 0.1143)
			(layers "B.Cu" "B.Mask" "B.Paste")
			(net "M_A_DQ56")
			(options
				(clearance outline)
				(anchor circle)
			)
			(primitives
				(gr_poly
					(pts
						(xy 0 -0.9017) (xy -0.03175 -0.89916) (xy -0.0635 -0.889) (xy -0.09144 -0.87376) (xy -0.11684 -0.85344)
						(xy -0.13716 -0.82804) (xy -0.1524 -0.8001) (xy -0.16256 -0.76835) (xy -0.1651 -0.7366) (xy -0.1651 -0.19685)
						(xy -0.17272 -0.18923) (xy -0.17907 -0.18034) (xy -0.18669 -0.17145) (xy -0.19177 -0.16256) (xy -0.19812 -0.15367)
						(xy -0.20828 -0.13335) (xy -0.21971 -0.10287) (xy -0.22225 -0.09271) (xy -0.22479 -0.08128) (xy -0.22606 -0.07112)
						(xy -0.2286 -0.05969) (xy -0.2286 -0.01651) (xy -0.22606 -0.00508) (xy -0.22479 0.00508) (xy -0.22225 0.01651)
						(xy -0.21971 0.02667) (xy -0.20828 0.05715) (xy -0.19812 0.07747) (xy -0.19177 0.08636) (xy -0.18669 0.09525)
						(xy -0.17907 0.10414) (xy -0.17272 0.11303) (xy -0.1651 0.12065) (xy -0.1651 0.7366) (xy -0.16256 0.76835)
						(xy -0.1524 0.8001) (xy -0.13716 0.82804) (xy -0.11684 0.85344) (xy -0.09144 0.87376) (xy -0.0635 0.889)
						(xy -0.03175 0.89916) (xy 0 0.9017) (xy 0.03175 0.89916) (xy 0.0635 0.889) (xy 0.09144 0.87376)
						(xy 0.11684 0.85344) (xy 0.13716 0.82804) (xy 0.1524 0.8001) (xy 0.16256 0.76835) (xy 0.1651 0.7366)
						(xy 0.1651 0.11938) (xy 0.17272 0.11176) (xy 0.19812 0.0762) (xy 0.2032 0.06604) (xy 0.20701 0.05715)
						(xy 0.21209 0.04699) (xy 0.2159 0.03683) (xy 0.21844 0.02667) (xy 0.22225 0.01524) (xy 0.22352 0.00508)
						(xy 0.22606 -0.00508) (xy 0.22733 -0.01651) (xy 0.22733 -0.02667) (xy 0.2286 -0.0381) (xy 0.22733 -0.04953)
						(xy 0.22733 -0.05969) (xy 0.22606 -0.07112) (xy 0.22352 -0.08128) (xy 0.22225 -0.09144) (xy 0.21844 -0.10287)
						(xy 0.2159 -0.11303) (xy 0.21209 -0.12319) (xy 0.20701 -0.13335) (xy 0.2032 -0.14224) (xy 0.19812 -0.1524)
						(xy 0.17272 -0.18796) (xy 0.1651 -0.19558) (xy 0.1651 -0.7366) (xy 0.16256 -0.76835) (xy 0.1524 -0.8001)
						(xy 0.13716 -0.82804) (xy 0.11684 -0.85344) (xy 0.09144 -0.87376) (xy 0.0635 -0.889) (xy 0.03175 -0.89916)
					)
					(width 0)
					(fill yes)
				)
			)
		)
		(pad "184" smd custom
			(at 25.649936 4.100068)
			(size 0.1143 0.1143)
			(layers "B.Cu" "B.Mask" "B.Paste")
			(net "GND")
			(options
				(clearance outline)
				(anchor circle)
			)
			(primitives
				(gr_poly
					(pts
						(xy 0 -0.9017) (xy -0.03175 -0.89916) (xy -0.0635 -0.889) (xy -0.09144 -0.87376) (xy -0.11684 -0.85344)
						(xy -0.13716 -0.82804) (xy -0.1524 -0.8001) (xy -0.16256 -0.76835) (xy -0.1651 -0.7366) (xy -0.1651 -0.11938)
						(xy -0.17272 -0.11176) (xy -0.19812 -0.0762) (xy -0.2032 -0.06604) (xy -0.20701 -0.05715) (xy -0.21209 -0.04699)
						(xy -0.2159 -0.03683) (xy -0.21844 -0.02667) (xy -0.22225 -0.01524) (xy -0.22352 -0.00508) (xy -0.22606 0.00508)
						(xy -0.22733 0.01651) (xy -0.22733 0.02667) (xy -0.2286 0.0381) (xy -0.22733 0.04953) (xy -0.22733 0.05969)
						(xy -0.22606 0.07112) (xy -0.22352 0.08128) (xy -0.22225 0.09144) (xy -0.21844 0.10287) (xy -0.2159 0.11303)
						(xy -0.21209 0.12319) (xy -0.20701 0.13335) (xy -0.2032 0.14224) (xy -0.19812 0.1524) (xy -0.17272 0.18796)
						(xy -0.1651 0.19558) (xy -0.1651 0.7366) (xy -0.16256 0.76835) (xy -0.1524 0.8001) (xy -0.13716 0.82804)
						(xy -0.11684 0.85344) (xy -0.09144 0.87376) (xy -0.0635 0.889) (xy -0.03175 0.89916) (xy 0 0.9017)
						(xy 0.03175 0.89916) (xy 0.0635 0.889) (xy 0.09144 0.87376) (xy 0.11684 0.85344) (xy 0.13716 0.82804)
						(xy 0.1524 0.8001) (xy 0.16256 0.76835) (xy 0.1651 0.7366) (xy 0.1651 0.19685) (xy 0.17272 0.18923)
						(xy 0.17907 0.18034) (xy 0.18669 0.17145) (xy 0.19177 0.16256) (xy 0.19812 0.15367) (xy 0.20828 0.13335)
						(xy 0.21971 0.10287) (xy 0.22225 0.09271) (xy 0.22479 0.08128) (xy 0.22606 0.07112) (xy 0.2286 0.05969)
						(xy 0.2286 0.01651) (xy 0.22606 0.00508) (xy 0.22479 -0.00508) (xy 0.22225 -0.01651) (xy 0.21971 -0.02667)
						(xy 0.20828 -0.05715) (xy 0.19812 -0.07747) (xy 0.19177 -0.08636) (xy 0.18669 -0.09525) (xy 0.17907 -0.10414)
						(xy 0.17272 -0.11303) (xy 0.1651 -0.12065) (xy 0.1651 -0.7366) (xy 0.16256 -0.76835) (xy 0.1524 -0.8001)
						(xy 0.13716 -0.82804) (xy 0.11684 -0.85344) (xy 0.09144 -0.87376) (xy 0.0635 -0.889) (xy 0.03175 -0.89916)
					)
					(width 0)
					(fill yes)
				)
			)
		)
		(pad "185" smd custom
			(at 25.94991 -4.100068)
			(size 0.1143 0.1143)
			(layers "B.Cu" "B.Mask" "B.Paste")
			(net "M_A_DQ57")
			(options
				(clearance outline)
				(anchor circle)
			)
			(primitives
				(gr_poly
					(pts
						(xy 0 -0.9017) (xy -0.03175 -0.89916) (xy -0.0635 -0.889) (xy -0.09144 -0.87376) (xy -0.11684 -0.85344)
						(xy -0.13716 -0.82804) (xy -0.1524 -0.8001) (xy -0.16256 -0.76835) (xy -0.1651 -0.7366) (xy -0.1651 -0.44958)
						(xy -0.17272 -0.44196) (xy -0.19812 -0.4064) (xy -0.2032 -0.39624) (xy -0.20701 -0.38735) (xy -0.21209 -0.37719)
						(xy -0.2159 -0.36703) (xy -0.21844 -0.35687) (xy -0.22225 -0.34544) (xy -0.22352 -0.33528) (xy -0.22606 -0.32512)
						(xy -0.22733 -0.31369) (xy -0.22733 -0.30353) (xy -0.2286 -0.2921) (xy -0.22733 -0.28067) (xy -0.22733 -0.27051)
						(xy -0.22606 -0.25908) (xy -0.22352 -0.24892) (xy -0.22225 -0.23876) (xy -0.21844 -0.22733) (xy -0.2159 -0.21717)
						(xy -0.21209 -0.20701) (xy -0.20701 -0.19685) (xy -0.2032 -0.18796) (xy -0.19812 -0.1778) (xy -0.17272 -0.14224)
						(xy -0.1651 -0.13462) (xy -0.1651 0.7366) (xy -0.16256 0.76835) (xy -0.1524 0.8001) (xy -0.13716 0.82804)
						(xy -0.11684 0.85344) (xy -0.09144 0.87376) (xy -0.0635 0.889) (xy -0.03175 0.89916) (xy 0 0.9017)
						(xy 0.03175 0.89916) (xy 0.0635 0.889) (xy 0.09144 0.87376) (xy 0.11684 0.85344) (xy 0.13716 0.82804)
						(xy 0.1524 0.8001) (xy 0.16256 0.76835) (xy 0.1651 0.7366) (xy 0.1651 -0.13462) (xy 0.17272 -0.14224)
						(xy 0.19812 -0.1778) (xy 0.2032 -0.18796) (xy 0.20701 -0.19685) (xy 0.21209 -0.20701) (xy 0.2159 -0.21717)
						(xy 0.21844 -0.22733) (xy 0.22225 -0.23876) (xy 0.22352 -0.24892) (xy 0.22606 -0.25908) (xy 0.22733 -0.27051)
						(xy 0.22733 -0.28067) (xy 0.2286 -0.2921) (xy 0.22733 -0.30353) (xy 0.22733 -0.31369) (xy 0.22606 -0.32512)
						(xy 0.22352 -0.33528) (xy 0.22225 -0.34544) (xy 0.21844 -0.35687) (xy 0.2159 -0.36703) (xy 0.21209 -0.37719)
						(xy 0.20701 -0.38735) (xy 0.2032 -0.39624) (xy 0.19812 -0.4064) (xy 0.17272 -0.44196) (xy 0.1651 -0.44958)
						(xy 0.1651 -0.7366) (xy 0.16256 -0.76835) (xy 0.1524 -0.8001) (xy 0.13716 -0.82804) (xy 0.11684 -0.85344)
						(xy 0.09144 -0.87376) (xy 0.0635 -0.889) (xy 0.03175 -0.89916)
					)
					(width 0)
					(fill yes)
				)
			)
		)
		(pad "186" smd custom
			(at 26.249884 4.100068)
			(size 0.1143 0.1143)
			(layers "B.Cu" "B.Mask" "B.Paste")
			(net "M_A_DQS_DN7")
			(options
				(clearance outline)
				(anchor circle)
			)
			(primitives
				(gr_poly
					(pts
						(xy 0 -0.9017) (xy -0.03175 -0.89916) (xy -0.0635 -0.889) (xy -0.09144 -0.87376) (xy -0.11684 -0.85344)
						(xy -0.13716 -0.82804) (xy -0.1524 -0.8001) (xy -0.16256 -0.76835) (xy -0.1651 -0.7366) (xy -0.1651 0.13462)
						(xy -0.17272 0.14224) (xy -0.19812 0.1778) (xy -0.2032 0.18796) (xy -0.20701 0.19685) (xy -0.21209 0.20701)
						(xy -0.2159 0.21717) (xy -0.21844 0.22733) (xy -0.22225 0.23876) (xy -0.22352 0.24892) (xy -0.22606 0.25908)
						(xy -0.22733 0.27051) (xy -0.22733 0.28067) (xy -0.2286 0.2921) (xy -0.22733 0.30353) (xy -0.22733 0.31369)
						(xy -0.22606 0.32512) (xy -0.22352 0.33528) (xy -0.22225 0.34544) (xy -0.21844 0.35687) (xy -0.2159 0.36703)
						(xy -0.21209 0.37719) (xy -0.20701 0.38735) (xy -0.2032 0.39624) (xy -0.19812 0.4064) (xy -0.17272 0.44196)
						(xy -0.1651 0.44958) (xy -0.1651 0.7366) (xy -0.16256 0.76835) (xy -0.1524 0.8001) (xy -0.13716 0.82804)
						(xy -0.11684 0.85344) (xy -0.09144 0.87376) (xy -0.0635 0.889) (xy -0.03175 0.89916) (xy 0 0.9017)
						(xy 0.03175 0.89916) (xy 0.0635 0.889) (xy 0.09144 0.87376) (xy 0.11684 0.85344) (xy 0.13716 0.82804)
						(xy 0.1524 0.8001) (xy 0.16256 0.76835) (xy 0.1651 0.7366) (xy 0.1651 0.44958) (xy 0.17272 0.44196)
						(xy 0.19812 0.4064) (xy 0.2032 0.39624) (xy 0.20701 0.38735) (xy 0.21209 0.37719) (xy 0.2159 0.36703)
						(xy 0.21844 0.35687) (xy 0.22225 0.34544) (xy 0.22352 0.33528) (xy 0.22606 0.32512) (xy 0.22733 0.31369)
						(xy 0.22733 0.30353) (xy 0.2286 0.2921) (xy 0.22733 0.28067) (xy 0.22733 0.27051) (xy 0.22606 0.25908)
						(xy 0.22352 0.24892) (xy 0.22225 0.23876) (xy 0.21844 0.22733) (xy 0.2159 0.21717) (xy 0.21209 0.20701)
						(xy 0.20701 0.19685) (xy 0.2032 0.18796) (xy 0.19812 0.1778) (xy 0.17272 0.14224) (xy 0.1651 0.13462)
						(xy 0.1651 -0.7366) (xy 0.16256 -0.76835) (xy 0.1524 -0.8001) (xy 0.13716 -0.82804) (xy 0.11684 -0.85344)
						(xy 0.09144 -0.87376) (xy 0.0635 -0.889) (xy 0.03175 -0.89916)
					)
					(width 0)
					(fill yes)
				)
			)
		)
		(pad "187" smd custom
			(at 26.550112 -4.100068)
			(size 0.1143 0.1143)
			(layers "B.Cu" "B.Mask" "B.Paste")
			(net "GND")
			(options
				(clearance outline)
				(anchor circle)
			)
			(primitives
				(gr_poly
					(pts
						(xy 0 -0.9017) (xy -0.03175 -0.89916) (xy -0.0635 -0.889) (xy -0.09144 -0.87376) (xy -0.11684 -0.85344)
						(xy -0.13716 -0.82804) (xy -0.1524 -0.8001) (xy -0.16256 -0.76835) (xy -0.1651 -0.7366) (xy -0.1651 -0.19685)
						(xy -0.17272 -0.18923) (xy -0.17907 -0.18034) (xy -0.18669 -0.17145) (xy -0.19177 -0.16256) (xy -0.19812 -0.15367)
						(xy -0.20828 -0.13335) (xy -0.21971 -0.10287) (xy -0.22225 -0.09271) (xy -0.22479 -0.08128) (xy -0.22606 -0.07112)
						(xy -0.2286 -0.05969) (xy -0.2286 -0.01651) (xy -0.22606 -0.00508) (xy -0.22479 0.00508) (xy -0.22225 0.01651)
						(xy -0.21971 0.02667) (xy -0.20828 0.05715) (xy -0.19812 0.07747) (xy -0.19177 0.08636) (xy -0.18669 0.09525)
						(xy -0.17907 0.10414) (xy -0.17272 0.11303) (xy -0.1651 0.12065) (xy -0.1651 0.7366) (xy -0.16256 0.76835)
						(xy -0.1524 0.8001) (xy -0.13716 0.82804) (xy -0.11684 0.85344) (xy -0.09144 0.87376) (xy -0.0635 0.889)
						(xy -0.03175 0.89916) (xy 0 0.9017) (xy 0.03175 0.89916) (xy 0.0635 0.889) (xy 0.09144 0.87376)
						(xy 0.11684 0.85344) (xy 0.13716 0.82804) (xy 0.1524 0.8001) (xy 0.16256 0.76835) (xy 0.1651 0.7366)
						(xy 0.1651 0.11938) (xy 0.17272 0.11176) (xy 0.19812 0.0762) (xy 0.2032 0.06604) (xy 0.20701 0.05715)
						(xy 0.21209 0.04699) (xy 0.2159 0.03683) (xy 0.21844 0.02667) (xy 0.22225 0.01524) (xy 0.22352 0.00508)
						(xy 0.22606 -0.00508) (xy 0.22733 -0.01651) (xy 0.22733 -0.02667) (xy 0.2286 -0.0381) (xy 0.22733 -0.04953)
						(xy 0.22733 -0.05969) (xy 0.22606 -0.07112) (xy 0.22352 -0.08128) (xy 0.22225 -0.09144) (xy 0.21844 -0.10287)
						(xy 0.2159 -0.11303) (xy 0.21209 -0.12319) (xy 0.20701 -0.13335) (xy 0.2032 -0.14224) (xy 0.19812 -0.1524)
						(xy 0.17272 -0.18796) (xy 0.1651 -0.19558) (xy 0.1651 -0.7366) (xy 0.16256 -0.76835) (xy 0.1524 -0.8001)
						(xy 0.13716 -0.82804) (xy 0.11684 -0.85344) (xy 0.09144 -0.87376) (xy 0.0635 -0.889) (xy 0.03175 -0.89916)
					)
					(width 0)
					(fill yes)
				)
			)
		)
		(pad "188" smd custom
			(at 26.850086 4.100068)
			(size 0.1143 0.1143)
			(layers "B.Cu" "B.Mask" "B.Paste")
			(net "M_A_DQS_DP7")
			(options
				(clearance outline)
				(anchor circle)
			)
			(primitives
				(gr_poly
					(pts
						(xy 0 -0.9017) (xy -0.03175 -0.89916) (xy -0.0635 -0.889) (xy -0.09144 -0.87376) (xy -0.11684 -0.85344)
						(xy -0.13716 -0.82804) (xy -0.1524 -0.8001) (xy -0.16256 -0.76835) (xy -0.1651 -0.7366) (xy -0.1651 -0.11938)
						(xy -0.17272 -0.11176) (xy -0.19812 -0.0762) (xy -0.2032 -0.06604) (xy -0.20701 -0.05715) (xy -0.21209 -0.04699)
						(xy -0.2159 -0.03683) (xy -0.21844 -0.02667) (xy -0.22225 -0.01524) (xy -0.22352 -0.00508) (xy -0.22606 0.00508)
						(xy -0.22733 0.01651) (xy -0.22733 0.02667) (xy -0.2286 0.0381) (xy -0.22733 0.04953) (xy -0.22733 0.05969)
						(xy -0.22606 0.07112) (xy -0.22352 0.08128) (xy -0.22225 0.09144) (xy -0.21844 0.10287) (xy -0.2159 0.11303)
						(xy -0.21209 0.12319) (xy -0.20701 0.13335) (xy -0.2032 0.14224) (xy -0.19812 0.1524) (xy -0.17272 0.18796)
						(xy -0.1651 0.19558) (xy -0.1651 0.7366) (xy -0.16256 0.76835) (xy -0.1524 0.8001) (xy -0.13716 0.82804)
						(xy -0.11684 0.85344) (xy -0.09144 0.87376) (xy -0.0635 0.889) (xy -0.03175 0.89916) (xy 0 0.9017)
						(xy 0.03175 0.89916) (xy 0.0635 0.889) (xy 0.09144 0.87376) (xy 0.11684 0.85344) (xy 0.13716 0.82804)
						(xy 0.1524 0.8001) (xy 0.16256 0.76835) (xy 0.1651 0.7366) (xy 0.1651 0.19685) (xy 0.17272 0.18923)
						(xy 0.17907 0.18034) (xy 0.18669 0.17145) (xy 0.19177 0.16256) (xy 0.19812 0.15367) (xy 0.20828 0.13335)
						(xy 0.21971 0.10287) (xy 0.22225 0.09271) (xy 0.22479 0.08128) (xy 0.22606 0.07112) (xy 0.2286 0.05969)
						(xy 0.2286 0.01651) (xy 0.22606 0.00508) (xy 0.22479 -0.00508) (xy 0.22225 -0.01651) (xy 0.21971 -0.02667)
						(xy 0.20828 -0.05715) (xy 0.19812 -0.07747) (xy 0.19177 -0.08636) (xy 0.18669 -0.09525) (xy 0.17907 -0.10414)
						(xy 0.17272 -0.11303) (xy 0.1651 -0.12065) (xy 0.1651 -0.7366) (xy 0.16256 -0.76835) (xy 0.1524 -0.8001)
						(xy 0.13716 -0.82804) (xy 0.11684 -0.85344) (xy 0.09144 -0.87376) (xy 0.0635 -0.889) (xy 0.03175 -0.89916)
					)
					(width 0)
					(fill yes)
				)
			)
		)
	)
)
